(kicad_pcb
	(version 20260206)
	(generator "pcbnew")
	(generator_version "10.0")
	(general
		(thickness 1.6)
		(legacy_teardrops no)
	)
	(paper "A4")
	(title_block
		(title "04192023_DAF0TMB3IC0_F0TG_MB_C_brd_V02_OCP.brd")
		(comment 1 "Grand Teton / footprints 7047-7053 of 8354")
	)
	(layers
		(0 "F.Cu" signal "TOP")
		(4 "In1.Cu" signal "GND")
		(6 "In2.Cu" signal "IN1")
		(8 "In3.Cu" signal "GND1")
		(10 "In4.Cu" signal "IN2")
		(12 "In5.Cu" signal "GND2")
		(14 "In6.Cu" signal "IN3")
		(16 "In7.Cu" signal "GND3")
		(18 "In8.Cu" signal "VCC")
		(20 "In9.Cu" signal "VCC1")
		(22 "In10.Cu" signal "GND4")
		(24 "In11.Cu" signal "IN4")
		(26 "In12.Cu" signal "GND5")
		(28 "In13.Cu" signal "IN5")
		(30 "In14.Cu" signal "GND6")
		(32 "In15.Cu" signal "IN6")
		(34 "In16.Cu" signal "GND7")
		(2 "B.Cu" signal "BOTTOM")
		(9 "F.Adhes" user "F.Adhesive")
		(11 "B.Adhes" user "B.Adhesive")
		(13 "F.Paste" user "Package Geometry/Pastemask Top")
		(15 "B.Paste" user "Package Geometry/Pastemask Bottom")
		(5 "F.SilkS" user "Ref Des/Silkscreen Top")
		(7 "B.SilkS" user "Ref Des/Silkscreen Bottom")
		(1 "F.Mask" user "Board Geometry/Soldermask Top")
		(3 "B.Mask" user "Board Geometry/Soldermask Bottom")
		(17 "Dwgs.User" user "User.Drawings")
		(19 "Cmts.User" user "User.Comments")
		(21 "Eco1.User" user "User.Eco1")
		(23 "Eco2.User" user "User.Eco2")
		(25 "Edge.Cuts" user "Board Geometry/Outline")
		(27 "Margin" user)
		(31 "F.CrtYd" user "Package Geometry/Place Bound Top")
		(29 "B.CrtYd" user "Package Geometry/Place Bound Bottom")
		(35 "F.Fab" user "Ref Des/Assembly Top")
		(33 "B.Fab" user "Ref Des/Assembly Bottom")
	)
	(footprint ""
		(layer "B.Cu")
		(at 460.405988 -43.400726 180)
		(property "Reference" "PR8073"
			(at 0 0 0)
			(layer "B.SilkS")
			(hide yes)
			(effects
				(font
					(size 1.27 1.27)
				)
				(justify mirror)
			)
		)
		(property "Value" ""
			(at 0 0 0)
			(layer "B.Fab")
			(effects
				(font
					(size 1.27 1.27)
				)
				(justify mirror)
			)
		)
		(duplicate_pad_numbers_are_jumpers no)
		(fp_line
			(start 0.7874 0.4064)
			(end 0.7874 -0.4064)
			(stroke
				(width 0.1524)
				(type default)
			)
			(layer "B.SilkS")
		)
		(fp_line
			(start 0.7874 -0.4064)
			(end -0.7874 -0.4064)
			(stroke
				(width 0.1524)
				(type default)
			)
			(layer "B.SilkS")
		)
		(fp_line
			(start -0.7874 0.4064)
			(end 0.7874 0.4064)
			(stroke
				(width 0.1524)
				(type default)
			)
			(layer "B.SilkS")
		)
		(fp_line
			(start -0.7874 -0.4064)
			(end -0.7874 0.4064)
			(stroke
				(width 0.1524)
				(type default)
			)
			(layer "B.SilkS")
		)
		(fp_line
			(start 0.67945 0.3048)
			(end 0.67945 -0.305054)
			(stroke
				(width 0.1)
				(type default)
			)
			(layer "B.Fab")
		)
		(fp_line
			(start 0.67945 -0.305054)
			(end 0.12065 -0.305054)
			(stroke
				(width 0.1)
				(type default)
			)
			(layer "B.Fab")
		)
		(fp_line
			(start 0.12065 0.3048)
			(end 0.67945 0.3048)
			(stroke
				(width 0.1)
				(type default)
			)
			(layer "B.Fab")
		)
		(fp_line
			(start 0.12065 0.2794)
			(end 0.12065 0.3048)
			(stroke
				(width 0.1)
				(type default)
			)
			(layer "B.Fab")
		)
		(fp_line
			(start 0.12065 -0.2794)
			(end -0.12065 -0.2794)
			(stroke
				(width 0.1)
				(type default)
			)
			(layer "B.Fab")
		)
		(fp_line
			(start 0.12065 -0.305054)
			(end 0.12065 -0.2794)
			(stroke
				(width 0.1)
				(type default)
			)
			(layer "B.Fab")
		)
		(fp_line
			(start -0.120396 0.3048)
			(end -0.120396 0.2794)
			(stroke
				(width 0.1)
				(type default)
			)
			(layer "B.Fab")
		)
		(fp_line
			(start -0.120396 0.2794)
			(end 0.12065 0.2794)
			(stroke
				(width 0.1)
				(type default)
			)
			(layer "B.Fab")
		)
		(fp_line
			(start -0.12065 -0.2794)
			(end -0.12065 -0.3048)
			(stroke
				(width 0.1)
				(type default)
			)
			(layer "B.Fab")
		)
		(fp_line
			(start -0.12065 -0.3048)
			(end -0.67945 -0.3048)
			(stroke
				(width 0.1)
				(type default)
			)
			(layer "B.Fab")
		)
		(fp_line
			(start -0.67945 0.3048)
			(end -0.120396 0.3048)
			(stroke
				(width 0.1)
				(type default)
			)
			(layer "B.Fab")
		)
		(fp_line
			(start -0.67945 -0.3048)
			(end -0.67945 0.3048)
			(stroke
				(width 0.1)
				(type default)
			)
			(layer "B.Fab")
		)
		(pad "1" smd circle
			(at 0.40005 0)
			(size 0 0)
			(layers "B.Cu" "B.Mask" "B.Paste")
			(net "P3V3_AUX")
		)
		(pad "2" smd circle
			(at -0.40005 0)
			(size 0 0)
			(layers "B.Cu" "B.Mask" "B.Paste")
			(net "PWRGD_P3V3_AUX_R1")
		)
	)
	(footprint ""
		(layer "B.Cu")
		(at 182.541164 -23.655782 -90)
		(property "Reference" "R3241"
			(at 0 0 90)
			(layer "B.SilkS")
			(hide yes)
			(effects
				(font
					(size 1.27 1.27)
				)
				(justify mirror)
			)
		)
		(property "Value" ""
			(at 0 0 90)
			(layer "B.Fab")
			(effects
				(font
					(size 1.27 1.27)
				)
				(justify mirror)
			)
		)
		(duplicate_pad_numbers_are_jumpers no)
		(fp_line
			(start -0.7874 0.4064)
			(end 0.7874 0.4064)
			(stroke
				(width 0.1524)
				(type default)
			)
			(layer "B.SilkS")
		)
		(fp_line
			(start 0.7874 0.4064)
			(end 0.7874 -0.4064)
			(stroke
				(width 0.1524)
				(type default)
			)
			(layer "B.SilkS")
		)
		(fp_line
			(start -0.7874 -0.4064)
			(end -0.7874 0.4064)
			(stroke
				(width 0.1524)
				(type default)
			)
			(layer "B.SilkS")
		)
		(fp_line
			(start 0.7874 -0.4064)
			(end -0.7874 -0.4064)
			(stroke
				(width 0.1524)
				(type default)
			)
			(layer "B.SilkS")
		)
		(fp_line
			(start -0.67945 0.3048)
			(end -0.120396 0.3048)
			(stroke
				(width 0.1)
				(type default)
			)
			(layer "B.Fab")
		)
		(fp_line
			(start -0.120396 0.3048)
			(end -0.120396 0.2794)
			(stroke
				(width 0.1)
				(type default)
			)
			(layer "B.Fab")
		)
		(fp_line
			(start 0.12065 0.3048)
			(end 0.67945 0.3048)
			(stroke
				(width 0.1)
				(type default)
			)
			(layer "B.Fab")
		)
		(fp_line
			(start 0.67945 0.3048)
			(end 0.67945 -0.305054)
			(stroke
				(width 0.1)
				(type default)
			)
			(layer "B.Fab")
		)
		(fp_line
			(start -0.120396 0.2794)
			(end 0.12065 0.2794)
			(stroke
				(width 0.1)
				(type default)
			)
			(layer "B.Fab")
		)
		(fp_line
			(start 0.12065 0.2794)
			(end 0.12065 0.3048)
			(stroke
				(width 0.1)
				(type default)
			)
			(layer "B.Fab")
		)
		(fp_line
			(start -0.12065 -0.2794)
			(end -0.12065 -0.3048)
			(stroke
				(width 0.1)
				(type default)
			)
			(layer "B.Fab")
		)
		(fp_line
			(start 0.12065 -0.2794)
			(end -0.12065 -0.2794)
			(stroke
				(width 0.1)
				(type default)
			)
			(layer "B.Fab")
		)
		(fp_line
			(start -0.67945 -0.3048)
			(end -0.67945 0.3048)
			(stroke
				(width 0.1)
				(type default)
			)
			(layer "B.Fab")
		)
		(fp_line
			(start -0.12065 -0.3048)
			(end -0.67945 -0.3048)
			(stroke
				(width 0.1)
				(type default)
			)
			(layer "B.Fab")
		)
		(fp_line
			(start 0.12065 -0.305054)
			(end 0.12065 -0.2794)
			(stroke
				(width 0.1)
				(type default)
			)
			(layer "B.Fab")
		)
		(fp_line
			(start 0.67945 -0.305054)
			(end 0.12065 -0.305054)
			(stroke
				(width 0.1)
				(type default)
			)
			(layer "B.Fab")
		)
		(pad "1" smd circle
			(at 0.40005 0 90)
			(size 0 0)
			(layers "B.Cu" "B.Mask" "B.Paste")
			(net "SMB_OCP_SFF_3V3AUX_SDA")
		)
		(pad "2" smd circle
			(at -0.40005 0 90)
			(size 0 0)
			(layers "B.Cu" "B.Mask" "B.Paste")
			(net "P3V3_AUX")
		)
	)
	(footprint ""
		(layer "B.Cu")
		(at 290.68268 -352.95332 90)
		(property "Reference" "PC7000"
			(at 0 0 90)
			(layer "B.SilkS")
			(hide yes)
			(effects
				(font
					(size 1.27 1.27)
				)
				(justify mirror)
			)
		)
		(property "Value" ""
			(at 0 0 90)
			(layer "B.Fab")
			(effects
				(font
					(size 1.27 1.27)
				)
				(justify mirror)
			)
		)
		(duplicate_pad_numbers_are_jumpers no)
		(fp_line
			(start 1.524 -0.762)
			(end -1.524 -0.762)
			(stroke
				(width 0.1524)
				(type default)
			)
			(layer "B.SilkS")
		)
		(fp_line
			(start -1.524 -0.762)
			(end -1.524 0.762)
			(stroke
				(width 0.1524)
				(type default)
			)
			(layer "B.SilkS")
		)
		(fp_line
			(start 1.524 0.762)
			(end 1.524 -0.762)
			(stroke
				(width 0.1524)
				(type default)
			)
			(layer "B.SilkS")
		)
		(fp_line
			(start -1.524 0.762)
			(end 1.524 0.762)
			(stroke
				(width 0.1524)
				(type default)
			)
			(layer "B.SilkS")
		)
		(fp_line
			(start 1.1049 -0.724916)
			(end 1.1049 0.724916)
			(stroke
				(width 0.1)
				(type default)
			)
			(layer "B.Fab")
		)
		(fp_line
			(start -1.1049 -0.724916)
			(end 1.1049 -0.724916)
			(stroke
				(width 0.1)
				(type default)
			)
			(layer "B.Fab")
		)
		(fp_line
			(start 1.1049 0.724916)
			(end -1.1049 0.724916)
			(stroke
				(width 0.1)
				(type default)
			)
			(layer "B.Fab")
		)
		(fp_line
			(start -1.1049 0.724916)
			(end -1.1049 -0.724916)
			(stroke
				(width 0.1)
				(type default)
			)
			(layer "B.Fab")
		)
		(pad "1" smd rect
			(at 0.889 0 90)
			(size 1.016 1.27)
			(layers "B.Cu" "B.Mask" "B.Paste")
			(net "SW_P12V_AUX_PVDDIO_P0_FLT")
		)
		(pad "2" smd rect
			(at -0.889 0 90)
			(size 1.016 1.27)
			(layers "B.Cu" "B.Mask" "B.Paste")
			(net "GND")
		)
	)
	(footprint ""
		(layer "B.Cu")
		(at 419.98265 -353.78009 -90)
		(property "Reference" "PR137"
			(at 0 0 90)
			(layer "B.SilkS")
			(hide yes)
			(effects
				(font
					(size 1.27 1.27)
				)
				(justify mirror)
			)
		)
		(property "Value" ""
			(at 0 0 90)
			(layer "B.Fab")
			(effects
				(font
					(size 1.27 1.27)
				)
				(justify mirror)
			)
		)
		(duplicate_pad_numbers_are_jumpers no)
		(fp_line
			(start -0.7874 0.4064)
			(end 0.7874 0.4064)
			(stroke
				(width 0.1524)
				(type default)
			)
			(layer "B.SilkS")
		)
		(fp_line
			(start 0.7874 0.4064)
			(end 0.7874 -0.4064)
			(stroke
				(width 0.1524)
				(type default)
			)
			(layer "B.SilkS")
		)
		(fp_line
			(start -0.7874 -0.4064)
			(end -0.7874 0.4064)
			(stroke
				(width 0.1524)
				(type default)
			)
			(layer "B.SilkS")
		)
		(fp_line
			(start 0.7874 -0.4064)
			(end -0.7874 -0.4064)
			(stroke
				(width 0.1524)
				(type default)
			)
			(layer "B.SilkS")
		)
		(fp_line
			(start -0.67945 0.3048)
			(end -0.120396 0.3048)
			(stroke
				(width 0.1)
				(type default)
			)
			(layer "B.Fab")
		)
		(fp_line
			(start -0.120396 0.3048)
			(end -0.120396 0.2794)
			(stroke
				(width 0.1)
				(type default)
			)
			(layer "B.Fab")
		)
		(fp_line
			(start 0.12065 0.3048)
			(end 0.67945 0.3048)
			(stroke
				(width 0.1)
				(type default)
			)
			(layer "B.Fab")
		)
		(fp_line
			(start 0.67945 0.3048)
			(end 0.67945 -0.305054)
			(stroke
				(width 0.1)
				(type default)
			)
			(layer "B.Fab")
		)
		(fp_line
			(start -0.120396 0.2794)
			(end 0.12065 0.2794)
			(stroke
				(width 0.1)
				(type default)
			)
			(layer "B.Fab")
		)
		(fp_line
			(start 0.12065 0.2794)
			(end 0.12065 0.3048)
			(stroke
				(width 0.1)
				(type default)
			)
			(layer "B.Fab")
		)
		(fp_line
			(start -0.12065 -0.2794)
			(end -0.12065 -0.3048)
			(stroke
				(width 0.1)
				(type default)
			)
			(layer "B.Fab")
		)
		(fp_line
			(start 0.12065 -0.2794)
			(end -0.12065 -0.2794)
			(stroke
				(width 0.1)
				(type default)
			)
			(layer "B.Fab")
		)
		(fp_line
			(start -0.67945 -0.3048)
			(end -0.67945 0.3048)
			(stroke
				(width 0.1)
				(type default)
			)
			(layer "B.Fab")
		)
		(fp_line
			(start -0.12065 -0.3048)
			(end -0.67945 -0.3048)
			(stroke
				(width 0.1)
				(type default)
			)
			(layer "B.Fab")
		)
		(fp_line
			(start 0.12065 -0.305054)
			(end 0.12065 -0.2794)
			(stroke
				(width 0.1)
				(type default)
			)
			(layer "B.Fab")
		)
		(fp_line
			(start 0.67945 -0.305054)
			(end 0.12065 -0.305054)
			(stroke
				(width 0.1)
				(type default)
			)
			(layer "B.Fab")
		)
		(pad "1" smd circle
			(at 0.40005 0 90)
			(size 0 0)
			(layers "B.Cu" "B.Mask" "B.Paste")
			(net "PVDD11_S3_P0_VOS1")
		)
		(pad "2" smd circle
			(at -0.40005 0 90)
			(size 0 0)
			(layers "B.Cu" "B.Mask" "B.Paste")
			(net "PVDD11_S3_P0")
		)
	)
	(footprint ""
		(layer "B.Cu")
		(at 346.036646 -416.899344 90)
		(property "Reference" "C6559"
			(at 0 0 90)
			(layer "B.SilkS")
			(hide yes)
			(effects
				(font
					(size 1.27 1.27)
				)
				(justify mirror)
			)
		)
		(property "Value" ""
			(at 0 0 90)
			(layer "B.Fab")
			(effects
				(font
					(size 1.27 1.27)
				)
				(justify mirror)
			)
		)
		(duplicate_pad_numbers_are_jumpers no)
		(fp_line
			(start 0.299974 -0.150114)
			(end -0.299974 -0.150114)
			(stroke
				(width 0.1)
				(type default)
			)
			(layer "B.Fab")
		)
		(fp_line
			(start -0.299974 -0.150114)
			(end -0.299974 0.150114)
			(stroke
				(width 0.1)
				(type default)
			)
			(layer "B.Fab")
		)
		(fp_line
			(start 0.299974 0.150114)
			(end 0.299974 -0.150114)
			(stroke
				(width 0.1)
				(type default)
			)
			(layer "B.Fab")
		)
		(fp_line
			(start -0.299974 0.150114)
			(end 0.299974 0.150114)
			(stroke
				(width 0.1)
				(type default)
			)
			(layer "B.Fab")
		)
		(pad "1" smd rect
			(at 0.2667 0 270)
			(size 0.3048 0.381)
			(layers "B.Cu" "B.Mask" "B.Paste")
			(net "P5E_CPU0_P1_TX_BUF_C_DP<13>")
		)
		(pad "2" smd rect
			(at -0.2667 0 270)
			(size 0.3048 0.381)
			(layers "B.Cu" "B.Mask" "B.Paste")
			(net "P5E_CPU0_P1_TX_BUF_DP<13>")
		)
	)
	(footprint ""
		(layer "B.Cu")
		(at 115.93322 -267.529564)
		(property "Reference" "C2352"
			(at 0 0 0)
			(layer "B.SilkS")
			(hide yes)
			(effects
				(font
					(size 1.27 1.27)
				)
				(justify mirror)
			)
		)
		(property "Value" ""
			(at 0 0 0)
			(layer "B.Fab")
			(effects
				(font
					(size 1.27 1.27)
				)
				(justify mirror)
			)
		)
		(duplicate_pad_numbers_are_jumpers no)
		(fp_line
			(start -0.7874 -0.4064)
			(end -0.7874 0.4064)
			(stroke
				(width 0.1524)
				(type default)
			)
			(layer "B.SilkS")
		)
		(fp_line
			(start -0.7874 0.4064)
			(end 0.7874 0.4064)
			(stroke
				(width 0.1524)
				(type default)
			)
			(layer "B.SilkS")
		)
		(fp_line
			(start 0.7874 -0.4064)
			(end -0.7874 -0.4064)
			(stroke
				(width 0.1524)
				(type default)
			)
			(layer "B.SilkS")
		)
		(fp_line
			(start 0.7874 0.4064)
			(end 0.7874 -0.4064)
			(stroke
				(width 0.1524)
				(type default)
			)
			(layer "B.SilkS")
		)
		(fp_line
			(start -0.67945 -0.3048)
			(end -0.67945 0.3048)
			(stroke
				(width 0.1)
				(type default)
			)
			(layer "B.Fab")
		)
		(fp_line
			(start -0.67945 0.3048)
			(end -0.120396 0.3048)
			(stroke
				(width 0.1)
				(type default)
			)
			(layer "B.Fab")
		)
		(fp_line
			(start -0.12065 -0.3048)
			(end -0.67945 -0.3048)
			(stroke
				(width 0.1)
				(type default)
			)
			(layer "B.Fab")
		)
		(fp_line
			(start -0.12065 -0.2794)
			(end -0.12065 -0.3048)
			(stroke
				(width 0.1)
				(type default)
			)
			(layer "B.Fab")
		)
		(fp_line
			(start -0.120396 0.2794)
			(end 0.12065 0.2794)
			(stroke
				(width 0.1)
				(type default)
			)
			(layer "B.Fab")
		)
		(fp_line
			(start -0.120396 0.3048)
			(end -0.120396 0.2794)
			(stroke
				(width 0.1)
				(type default)
			)
			(layer "B.Fab")
		)
		(fp_line
			(start 0.12065 -0.305054)
			(end 0.12065 -0.2794)
			(stroke
				(width 0.1)
				(type default)
			)
			(layer "B.Fab")
		)
		(fp_line
			(start 0.12065 -0.2794)
			(end -0.12065 -0.2794)
			(stroke
				(width 0.1)
				(type default)
			)
			(layer "B.Fab")
		)
		(fp_line
			(start 0.12065 0.2794)
			(end 0.12065 0.3048)
			(stroke
				(width 0.1)
				(type default)
			)
			(layer "B.Fab")
		)
		(fp_line
			(start 0.12065 0.3048)
			(end 0.67945 0.3048)
			(stroke
				(width 0.1)
				(type default)
			)
			(layer "B.Fab")
		)
		(fp_line
			(start 0.67945 -0.305054)
			(end 0.12065 -0.305054)
			(stroke
				(width 0.1)
				(type default)
			)
			(layer "B.Fab")
		)
		(fp_line
			(start 0.67945 0.3048)
			(end 0.67945 -0.305054)
			(stroke
				(width 0.1)
				(type default)
			)
			(layer "B.Fab")
		)
		(pad "1" smd circle
			(at 0.40005 0 180)
			(size 0 0)
			(layers "B.Cu" "B.Mask" "B.Paste")
			(net "PVDDCR_CPU1_P1")
		)
		(pad "2" smd circle
			(at -0.40005 0 180)
			(size 0 0)
			(layers "B.Cu" "B.Mask" "B.Paste")
			(net "GND")
		)
	)
	(footprint ""
		(layer "B.Cu")
		(at 167.936418 -349.716344)
		(property "Reference" "PR376"
			(at 0 0 0)
			(layer "B.SilkS")
			(hide yes)
			(effects
				(font
					(size 1.27 1.27)
				)
				(justify mirror)
			)
		)
		(property "Value" ""
			(at 0 0 0)
			(layer "B.Fab")
			(effects
				(font
					(size 1.27 1.27)
				)
				(justify mirror)
			)
		)
		(duplicate_pad_numbers_are_jumpers no)
		(fp_line
			(start -0.7874 -0.4064)
			(end -0.7874 0.4064)
			(stroke
				(width 0.1524)
				(type default)
			)
			(layer "B.SilkS")
		)
		(fp_line
			(start -0.7874 0.4064)
			(end 0.7874 0.4064)
			(stroke
				(width 0.1524)
				(type default)
			)
			(layer "B.SilkS")
		)
		(fp_line
			(start 0.7874 -0.4064)
			(end -0.7874 -0.4064)
			(stroke
				(width 0.1524)
				(type default)
			)
			(layer "B.SilkS")
		)
		(fp_line
			(start 0.7874 0.4064)
			(end 0.7874 -0.4064)
			(stroke
				(width 0.1524)
				(type default)
			)
			(layer "B.SilkS")
		)
		(fp_line
			(start -0.67945 -0.3048)
			(end -0.67945 0.3048)
			(stroke
				(width 0.1)
				(type default)
			)
			(layer "B.Fab")
		)
		(fp_line
			(start -0.67945 0.3048)
			(end -0.120396 0.3048)
			(stroke
				(width 0.1)
				(type default)
			)
			(layer "B.Fab")
		)
		(fp_line
			(start -0.12065 -0.3048)
			(end -0.67945 -0.3048)
			(stroke
				(width 0.1)
				(type default)
			)
			(layer "B.Fab")
		)
		(fp_line
			(start -0.12065 -0.2794)
			(end -0.12065 -0.3048)
			(stroke
				(width 0.1)
				(type default)
			)
			(layer "B.Fab")
		)
		(fp_line
			(start -0.120396 0.2794)
			(end 0.12065 0.2794)
			(stroke
				(width 0.1)
				(type default)
			)
			(layer "B.Fab")
		)
		(fp_line
			(start -0.120396 0.3048)
			(end -0.120396 0.2794)
			(stroke
				(width 0.1)
				(type default)
			)
			(layer "B.Fab")
		)
		(fp_line
			(start 0.12065 -0.305054)
			(end 0.12065 -0.2794)
			(stroke
				(width 0.1)
				(type default)
			)
			(layer "B.Fab")
		)
		(fp_line
			(start 0.12065 -0.2794)
			(end -0.12065 -0.2794)
			(stroke
				(width 0.1)
				(type default)
			)
			(layer "B.Fab")
		)
		(fp_line
			(start 0.12065 0.2794)
			(end 0.12065 0.3048)
			(stroke
				(width 0.1)
				(type default)
			)
			(layer "B.Fab")
		)
		(fp_line
			(start 0.12065 0.3048)
			(end 0.67945 0.3048)
			(stroke
				(width 0.1)
				(type default)
			)
			(layer "B.Fab")
		)
		(fp_line
			(start 0.67945 -0.305054)
			(end 0.12065 -0.305054)
			(stroke
				(width 0.1)
				(type default)
			)
			(layer "B.Fab")
		)
		(fp_line
			(start 0.67945 0.3048)
			(end 0.67945 -0.305054)
			(stroke
				(width 0.1)
				(type default)
			)
			(layer "B.Fab")
		)
		(pad "1" smd circle
			(at 0.40005 0 180)
			(size 0 0)
			(layers "B.Cu" "B.Mask" "B.Paste")
			(net "P5V_AUX")
		)
		(pad "2" smd circle
			(at -0.40005 0 180)
			(size 0 0)
			(layers "B.Cu" "B.Mask" "B.Paste")
			(net "PVDD11_S3_P1_VMON")
		)
	)
)
